# S9S_MB_2U (Grand Teton) — schematic netlist excerpt (pin names and nets, part order shuffled) for the footprints in the layout excerpt that follows; sources: Cadence DE-HDL packaged netlist, KiCad conversion of 03242023_DA0F0TMBIJ0_F0T_Motherboard_J_brd_V01_OCP.brd

J13  SCONN288_ADR50017P130CC  SCONN288_ADR50017-P130CC IO  pkg DDR288S_1-1VXB  page 94
  VIN_BULK0  = P12V_S3_AUX_CPU0_NVDIMM
  RFU0  = TP_CHG_CPU0_DIMM1_FRU_0
  VIN_MGMT  = P3V3_AUX
  HSCL  = I3C_SPD_DDREFGH_CPU0_LVC1_SCL_4
  HSDA  = I3C_SPD_DDREFGH_CPU0_LVC1_SDA
  VSS0  = GND
  DQ0_A  = M_G_CPU0_SA_DQ<0>
  VSS1  = GND
  DQ1_A  = M_G_CPU0_SA_DQ<1>
  VSS2  = GND
  DQS0_A_T  = M_G_CPU0_SA_DQS_DP<0>
  DQS0_A_C  = M_G_CPU0_SA_DQS_DN<0>
  VSS3  = GND
  DQ4_A  = M_G_CPU0_SA_DQ<4>
  VSS4  = GND
  DQ5_A  = M_G_CPU0_SA_DQ<5>
  VSS5  = GND
  DQ8_A  = M_G_CPU0_SA_DQ<8>
  VSS6  = GND
  DQ9_A  = M_G_CPU0_SA_DQ<9>
  VSS7  = GND
  DQS1_A_T  = M_G_CPU0_SA_DQS_DP<1>
  DQS1_A_C  = M_G_CPU0_SA_DQS_DN<1>
  VSS8  = GND
  DQ12_A  = M_G_CPU0_SA_DQ<12>
  VSS9  = GND
  DQ13_A  = M_G_CPU0_SA_DQ<13>
  VSS10  = GND
  DQ16_A  = M_G_CPU0_SA_DQ<16>
  VSS11  = GND
  DQ17_A  = M_G_CPU0_SA_DQ<17>
  VSS12  = GND
  DQS2_A_T  = M_G_CPU0_SA_DQS_DP<2>
  DQS2_A_C  = M_G_CPU0_SA_DQS_DN<2>
  VSS13  = GND
  DQ20_A  = M_G_CPU0_SA_DQ<20>
  VSS14  = GND
  DQ21_A  = M_G_CPU0_SA_DQ<21>
  VSS15  = GND
  DQ24_A  = M_G_CPU0_SA_DQ<24>
  VSS16  = GND
  DQ25_A  = M_G_CPU0_SA_DQ<25>
  VSS17  = GND
  DQS3_A_T  = M_G_CPU0_SA_DQS_DP<3>
  DQS3_A_C  = M_G_CPU0_SA_DQS_DN<3>
  VSS18  = GND
  DQ28_A  = M_G_CPU0_SA_DQ<28>
  VSS19  = GND
  DQ29_A  = M_G_CPU0_SA_DQ<29>
  VSS20  = GND
  CB0_A  = M_G_CPU0_SA_CB<0>
  VSS21  = GND
  CB1_A  = M_G_CPU0_SA_CB<1>
  VSS22  = GND
  DQS4_A_T  = M_G_CPU0_SA_DQS_DP<4>
  DQS4_A_C  = M_G_CPU0_SA_DQS_DN<4>
  VSS23  = GND
  CB4_A  = M_G_CPU0_SA_CB<4>
  VSS24  = GND
  CB5_A  = M_G_CPU0_SA_CB<5>
  VSS25  = GND
  ALERT_N  = M_G_CPU0_ALERT_N
  VSS26  = GND
  CS0_A_N  = M_G_CPU0_SA_CS_N<0>
  VSS27  = GND
  CA0_A  = M_G_CPU0_SA_CA<0>
  VSS28  = GND
  CA2_A  = M_G_CPU0_SA_CA<2>
  VSS29  = GND
  CA4_A  = M_G_CPU0_SA_CA<4>
  VSS30  = GND
  CA6_A  = M_G_CPU0_SA_CA<6>
  VSS31  = GND
  PAR_A  = M_G_CPU0_SA_PAR
  VSS32  = GND
  CA0_B  = M_G_CPU0_SB_CA<0>
  VSS33  = GND
  CA2_B  = M_G_CPU0_SB_CA<2>
  VSS34  = GND
  CA4_B  = M_G_CPU0_SB_CA<4>
  VSS35  = GND
  CA6_B  = M_G_CPU0_SB_CA<6>
  VSS36  = GND
  CS0_B_N  = M_G_CPU0_SB_CS_N<0>
  VSS37  = GND
  \lbd||rsp_a_n\  = M_G_CPU0_SA_RSP<0>
  \lbs||rsp_b_n\  = M_G_CPU0_SB_RSP<0>
  VSS38  = GND
  CB4_B  = M_G_CPU0_SB_CB<4>
  VSS39  = GND
  CB5_B  = M_G_CPU0_SB_CB<5>
  VSS40  = GND
  \dqs9_b_t||tdqs9_b_t||dbi4_b_n\  = M_G_CPU0_SB_DQS_DP<9>
  \dqs9_b_c||tdqs9_b_c\  = M_G_CPU0_SB_DQS_DN<9>
  VSS41  = GND
  CB0_B  = M_G_CPU0_SB_CB<0>
  VSS42  = GND
  CB1_B  = M_G_CPU0_SB_CB<1>
  VSS43  = GND
  DQ0_B  = M_G_CPU0_SB_DQ<0>
  VSS44  = GND
  DQ1_B  = M_G_CPU0_SB_DQ<1>
  VSS45  = GND
  DQS0_B_T  = M_G_CPU0_SB_DQS_DP<0>
  DQS0_B_C  = M_G_CPU0_SB_DQS_DN<0>
  VSS46  = GND
  DQ4_B  = M_G_CPU0_SB_DQ<4>
  VSS47  = GND
  DQ5_B  = M_G_CPU0_SB_DQ<5>
  VSS48  = GND
  DQ8_B  = M_G_CPU0_SB_DQ<8>
  VSS49  = GND
  DQ9_B  = M_G_CPU0_SB_DQ<9>
  VSS50  = GND
  DQS1_B_T  = M_G_CPU0_SB_DQS_DP<1>
  DQS1_B_C  = M_G_CPU0_SB_DQS_DN<1>
  VSS51  = GND
  DQ12_B  = M_G_CPU0_SB_DQ<12>
  VSS52  = GND
  DQ13_B  = M_G_CPU0_SB_DQ<13>
  VSS53  = GND
  DQ16_B  = M_G_CPU0_SB_DQ<16>
  VSS54  = GND
  DQ17_B  = M_G_CPU0_SB_DQ<17>
  VSS55  = GND
  DQS2_B_T  = M_G_CPU0_SB_DQS_DP<2>
  DQS2_B_C  = M_G_CPU0_SB_DQS_DN<2>
  VSS56  = GND
  DQ20_B  = M_G_CPU0_SB_DQ<20>
  VSS57  = GND
  DQ21_B  = M_G_CPU0_SB_DQ<21>
  VSS58  = GND
  DQ24_B  = M_G_CPU0_SB_DQ<24>
  VSS59  = GND
  DQ25_B  = M_G_CPU0_SB_DQ<25>
  VSS60  = GND
  DQS3_B_T  = M_G_CPU0_SB_DQS_DP<3>
  DQS3_B_C  = M_G_CPU0_SB_DQS_DN<3>
  VSS61  = GND
  DQ28_B  = M_G_CPU0_SB_DQ<28>
  VSS62  = GND
  DQ29_B  = M_G_CPU0_SB_DQ<29>
  VSS63  = GND
  RFU1  = TP_CHG_CPU0_DIMM1_FRU_1
  VIN_BULK1  = P12V_S3_AUX_CPU0_NVDIMM
  VIN_BULK2  = P12V_S3_AUX_CPU0_NVDIMM
  \pwr_good||fail_n\  = PWRGD_CHG_CPU0_DIMM1
  HSA  = PD_CHG_CPU0_DIMM1_SAA
  RFU2  = TP_CHG_CPU0_DIMM1_FRU_2
  RFU3  = TP_CHG_CPU0_DIMM1_FRU_3
  VSS64  = GND
  DQ2_A  = M_G_CPU0_SA_DQ<2>
  VSS65  = GND
  DQ3_A  = M_G_CPU0_SA_DQ<3>
  VSS66  = GND
  \dqs5_a_c||tdqs5_a_c||dqs5_a_t||tdqs5_a_t\  = M_G_CPU0_SA_DQS_DN<5>
  \dqs5_a_t||tdqs5_a_t\  = M_G_CPU0_SA_DQS_DP<5>
  VSS67  = GND
  DQ6_A  = M_G_CPU0_SA_DQ<6>
  VSS68  = GND
  DQ7_A  = M_G_CPU0_SA_DQ<7>
  VSS69  = GND
  DQ10_A  = M_G_CPU0_SA_DQ<10>
  VSS70  = GND
  DQ11_A  = M_G_CPU0_SA_DQ<11>
  VSS71  = GND
  \dqs6_a_c||tdqs6_a_c||dqs6_a_t||tdqs6_a_t\  = M_G_CPU0_SA_DQS_DN<6>
  \dqs6_a_t||tdqs6_a_t\  = M_G_CPU0_SA_DQS_DP<6>
  VSS72  = GND
  DQ14_A  = M_G_CPU0_SA_DQ<14>
  VSS73  = GND
  DQ15_A  = M_G_CPU0_SA_DQ<15>
  VSS74  = GND
  DQ18_A  = M_G_CPU0_SA_DQ<18>
  VSS75  = GND
  DQ19_A  = M_G_CPU0_SA_DQ<19>
  VSS76  = GND
  \dqs7_a_c||tdqs7_a_c\  = M_G_CPU0_SA_DQS_DN<7>
  \dqs7_a_t||tdqs7_a_t\  = M_G_CPU0_SA_DQS_DP<7>
  VSS77  = GND
  DQ22_A  = M_G_CPU0_SA_DQ<22>
  VSS78  = GND
  DQ23_A  = M_G_CPU0_SA_DQ<23>
  VSS79  = GND
  DQ26_A  = M_G_CPU0_SA_DQ<26>
  VSS80  = GND
  DQ27_A  = M_G_CPU0_SA_DQ<27>
  VSS81  = GND
  \dqs8_a_c||tdqs8_a_c\  = M_G_CPU0_SA_DQS_DN<8>
  \dqs8_a_t||tdqs8_a_t\  = M_G_CPU0_SA_DQS_DP<8>
  VSS82  = GND
  DQ30_A  = M_G_CPU0_SA_DQ<30>
  VSS83  = GND
  DQ31_A  = M_G_CPU0_SA_DQ<31>
  VSS84  = GND
  CB2_A  = M_G_CPU0_SA_CB<2>
  VSS85  = GND
  CB3_A  = M_G_CPU0_SA_CB<3>
  VSS86  = GND
  \dqs9_a_c||tdqs9_a_c\  = M_G_CPU0_SA_DQS_DN<9>
  \dqs9_a_t||tdqs9_a_t\  = M_G_CPU0_SA_DQS_DP<9>
  VSS87  = GND
  CB6_A  = M_G_CPU0_SA_CB<6>
  VSS88  = GND
  CB7_A  = M_G_CPU0_SA_CB<7>
  VSS89  = GND
  RESET_N  = RST_M_GH_CPU0_FPGA_N
  VSS90  = GND
  CS1_A_N  = M_G_CPU0_SA_CS_N<1>
  VSS91  = GND
  CA1_A  = M_G_CPU0_SA_CA<1>
  VSS92  = GND
  CA3_A  = M_G_CPU0_SA_CA<3>
  VSS93  = GND
  CA5_A  = M_G_CPU0_SA_CA<5>
  VSS94  = GND
  CK_T  = M_G_CPU0_CLK_DP<0>
  CK_C  = M_G_CPU0_CLK_DN<0>
  VSS95  = GND
  RFU4  = TP_CHG_CPU0_DIMM1_FRU_4
  CA1_B  = M_G_CPU0_SB_CA<1>
  VSS96  = GND
  CA3_B  = M_G_CPU0_SB_CA<3>
  VSS97  = GND
  CA5_B  = M_G_CPU0_SB_CA<5>
  VSS98  = GND
  PAR_B  = M_G_CPU0_SB_PAR
  VSS99  = GND
  CS1_B_N  = M_G_CPU0_SB_CS_N<1>
  VSS100  = GND
  RFU5  = TP_CHG_CPU0_DIMM1_FRU_5
  RFU6  = TP_CHG_CPU0_DIMM1_FRU_6
  VSS101  = GND
  CB6_B  = M_G_CPU0_SB_CB<6>
  VSS102  = GND
  CB7_B  = M_G_CPU0_SB_CB<7>
  VSS103  = GND
  DQS4_B_C  = M_G_CPU0_SB_DQS_DN<4>
  DQS4_B_T  = M_G_CPU0_SB_DQS_DP<4>
  VSS104  = GND
  CB2_B  = M_G_CPU0_SB_CB<2>
  VSS105  = GND
  CB3_B  = M_G_CPU0_SB_CB<3>
  VSS106  = GND
  DQ2_B  = M_G_CPU0_SB_DQ<2>
  VSS107  = GND
  DQ3_B  = M_G_CPU0_SB_DQ<3>
  VSS108  = GND
  \dqs5_b_c||tdqs5_b_c\  = M_G_CPU0_SB_DQS_DN<5>
  \dqs5_b_t||tdqs5_b_t\  = M_G_CPU0_SB_DQS_DP<5>
  VSS109  = GND
  DQ6_B  = M_G_CPU0_SB_DQ<6>
  VSS110  = GND
  DQ7_B  = M_G_CPU0_SB_DQ<7>
  VSS111  = GND
  DQ10_B  = M_G_CPU0_SB_DQ<10>
  VSS112  = GND
  DQ11_B  = M_G_CPU0_SB_DQ<11>
  VSS113  = GND
  \dqs6_b_c||tdqs6_b_c\  = M_G_CPU0_SB_DQS_DN<6>
  \dqs6_b_t||tdqs6_b_t\  = M_G_CPU0_SB_DQS_DP<6>
  VSS114  = GND
  DQ14_B  = M_G_CPU0_SB_DQ<14>
  VSS115  = GND
  DQ15_B  = M_G_CPU0_SB_DQ<15>
  VSS116  = GND
  DQ18_B  = M_G_CPU0_SB_DQ<18>
  VSS117  = GND
  DQ19_B  = M_G_CPU0_SB_DQ<19>
  VSS118  = GND
  \dqs7_b_c||tdqs7_b_c\  = M_G_CPU0_SB_DQS_DN<7>
  \dqs7_b_t||tdqs7_b_t\  = M_G_CPU0_SB_DQS_DP<7>
  VSS119  = GND
  DQ22_B  = M_G_CPU0_SB_DQ<22>
  VSS120  = GND
  DQ23_B  = M_G_CPU0_SB_DQ<23>
  VSS121  = GND
  DQ26_B  = M_G_CPU0_SB_DQ<26>
  VSS122  = GND
  DQ27_B  = M_G_CPU0_SB_DQ<27>
  VSS123  = GND
  \dqs8_b_c||tdqs8_b_c\  = M_G_CPU0_SB_DQS_DN<8>
  \dqs8_b_t||tdqs8_b_t\  = M_G_CPU0_SB_DQS_DP<8>
  VSS124  = GND
  DQ30_B  = M_G_CPU0_SB_DQ<30>
  VSS125  = GND
  DQ31_B  = M_G_CPU0_SB_DQ<31>
  VSS126  = GND
  G1  = GND
  G2  = GND
  G3  = GND

(kicad_pcb
	(version 20260206)
	(generator "pcbnew")
	(generator_version "10.0")
	(general
		(thickness 1.6)
		(legacy_teardrops no)
	)
	(paper "A4")
	(title_block
		(title "03242023_DA0F0TMBIJ0_F0T_Motherboard_J_brd_V01_OCP.brd")
		(comment 1 "Grand Teton / footprint 1368 of 6105 (J13), pads 138-182 of 291")
	)
	(layers
		(0 "F.Cu" signal "TOP")
		(4 "In1.Cu" signal "GND")
		(6 "In2.Cu" signal "IN1")
		(8 "In3.Cu" signal "GND1")
		(10 "In4.Cu" signal "IN2")
		(12 "In5.Cu" signal "GND2")
		(14 "In6.Cu" signal "IN3")
		(16 "In7.Cu" signal "GND3")
		(18 "In8.Cu" signal "VCC")
		(20 "In9.Cu" signal "VCC1")
		(22 "In10.Cu" signal "GND4")
		(24 "In11.Cu" signal "IN4")
		(26 "In12.Cu" signal "GND5")
		(28 "In13.Cu" signal "IN5")
		(30 "In14.Cu" signal "GND6")
		(32 "In15.Cu" signal "IN6")
		(34 "In16.Cu" signal "GND7")
		(2 "B.Cu" signal "BOTTOM")
		(9 "F.Adhes" user "F.Adhesive")
		(11 "B.Adhes" user "B.Adhesive")
		(13 "F.Paste" user "Package Geometry/Pastemask Top")
		(15 "B.Paste" user "Package Geometry/Pastemask Bottom")
		(5 "F.SilkS" user "Ref Des/Silkscreen Top")
		(7 "B.SilkS" user "Ref Des/Silkscreen Bottom")
		(1 "F.Mask" user "Board Geometry/Soldermask Top")
		(3 "B.Mask" user "Board Geometry/Soldermask Bottom")
		(17 "Dwgs.User" user "User.Drawings")
		(19 "Cmts.User" user "User.Comments")
		(21 "Eco1.User" user "User.Eco1")
		(23 "Eco2.User" user "User.Eco2")
		(25 "Edge.Cuts" user "Board Geometry/Outline")
		(27 "Margin" user)
		(31 "F.CrtYd" user "Package Geometry/Place Bound Top")
		(29 "B.CrtYd" user "Package Geometry/Place Bound Bottom")
		(35 "F.Fab" user "Ref Des/Assembly Top")
		(33 "B.Fab" user "Ref Des/Assembly Bottom")
	)
	(footprint ""
		(layer "F.Cu")
		(at 446.522348 -258.091686)
		(property "Reference" "J13"
			(at -3.683 -81.702148 0)
			(unlocked yes)
			(layer "F.SilkS")
			(effects
				(font
					(size 0.7874 0.5842)
					(thickness 0.1524)
				)
				(justify left)
			)
		)
		(property "Value" ""
			(at 0 0 0)
			(layer "F.Fab")
			(effects
				(font
					(size 1.27 1.27)
				)
			)
		)
		(duplicate_pad_numbers_are_jumpers no)
		(pad "138" smd rect
			(at -2.050034 58.224928 270)
			(size 0.519938 1.4986)
			(layers "F.Cu" "F.Mask" "F.Paste")
			(net "M_G_CPU0_SB_DQS_DN<3>")
		)
		(pad "139" smd rect
			(at -2.050034 59.075066 270)
			(size 0.519938 1.4986)
			(layers "F.Cu" "F.Mask" "F.Paste")
			(net "GND")
		)
		(pad "140" smd rect
			(at -2.050034 59.92495 270)
			(size 0.519938 1.4986)
			(layers "F.Cu" "F.Mask" "F.Paste")
			(net "M_G_CPU0_SB_DQ<28>")
		)
		(pad "141" smd rect
			(at -2.050034 60.775088 270)
			(size 0.519938 1.4986)
			(layers "F.Cu" "F.Mask" "F.Paste")
			(net "GND")
		)
		(pad "142" smd rect
			(at -2.050034 61.624972 270)
			(size 0.519938 1.4986)
			(layers "F.Cu" "F.Mask" "F.Paste")
			(net "M_G_CPU0_SB_DQ<29>")
		)
		(pad "143" smd rect
			(at -2.050034 62.47511 270)
			(size 0.519938 1.4986)
			(layers "F.Cu" "F.Mask" "F.Paste")
			(net "GND")
		)
		(pad "144" smd rect
			(at -2.050034 63.324994 270)
			(size 0.519938 1.4986)
			(layers "F.Cu" "F.Mask" "F.Paste")
			(net "TP_CHG_CPU0_DIMM1_FRU_1")
		)
		(pad "145" smd rect
			(at 2.050034 -63.324994 270)
			(size 0.519938 1.4986)
			(layers "F.Cu" "F.Mask" "F.Paste")
			(net "P12V_S3_AUX_CPU0_NVDIMM")
		)
		(pad "146" smd rect
			(at 2.050034 -62.47511 270)
			(size 0.519938 1.4986)
			(layers "F.Cu" "F.Mask" "F.Paste")
			(net "P12V_S3_AUX_CPU0_NVDIMM")
		)
		(pad "147" smd rect
			(at 2.050034 -61.624972 270)
			(size 0.519938 1.4986)
			(layers "F.Cu" "F.Mask" "F.Paste")
			(net "PWRGD_CHG_CPU0_DIMM1")
		)
		(pad "148" smd rect
			(at 2.050034 -60.775088 270)
			(size 0.519938 1.4986)
			(layers "F.Cu" "F.Mask" "F.Paste")
			(net "PD_CHG_CPU0_DIMM1_SAA")
		)
		(pad "149" smd rect
			(at 2.050034 -59.92495 270)
			(size 0.519938 1.4986)
			(layers "F.Cu" "F.Mask" "F.Paste")
			(net "TP_CHG_CPU0_DIMM1_FRU_2")
		)
		(pad "150" smd rect
			(at 2.050034 -59.075066 270)
			(size 0.519938 1.4986)
			(layers "F.Cu" "F.Mask" "F.Paste")
			(net "TP_CHG_CPU0_DIMM1_FRU_3")
		)
		(pad "151" smd rect
			(at 2.050034 -58.224928 270)
			(size 0.519938 1.4986)
			(layers "F.Cu" "F.Mask" "F.Paste")
			(net "GND")
		)
		(pad "152" smd rect
			(at 2.050034 -57.375044 270)
			(size 0.519938 1.4986)
			(layers "F.Cu" "F.Mask" "F.Paste")
			(net "M_G_CPU0_SA_DQ<2>")
		)
		(pad "153" smd rect
			(at 2.050034 -56.524906 270)
			(size 0.519938 1.4986)
			(layers "F.Cu" "F.Mask" "F.Paste")
			(net "GND")
		)
		(pad "154" smd rect
			(at 2.050034 -55.675022 270)
			(size 0.519938 1.4986)
			(layers "F.Cu" "F.Mask" "F.Paste")
			(net "M_G_CPU0_SA_DQ<3>")
		)
		(pad "155" smd rect
			(at 2.050034 -54.824884 270)
			(size 0.519938 1.4986)
			(layers "F.Cu" "F.Mask" "F.Paste")
			(net "GND")
		)
		(pad "156" smd rect
			(at 2.050034 -53.975 270)
			(size 0.519938 1.4986)
			(layers "F.Cu" "F.Mask" "F.Paste")
			(net "M_G_CPU0_SA_DQS_DN<5>")
		)
		(pad "157" smd rect
			(at 2.050034 -53.125116 270)
			(size 0.519938 1.4986)
			(layers "F.Cu" "F.Mask" "F.Paste")
			(net "M_G_CPU0_SA_DQS_DP<5>")
		)
		(pad "158" smd rect
			(at 2.050034 -52.274978 270)
			(size 0.519938 1.4986)
			(layers "F.Cu" "F.Mask" "F.Paste")
			(net "GND")
		)
		(pad "159" smd rect
			(at 2.050034 -51.425094 270)
			(size 0.519938 1.4986)
			(layers "F.Cu" "F.Mask" "F.Paste")
			(net "M_G_CPU0_SA_DQ<6>")
		)
		(pad "160" smd rect
			(at 2.050034 -50.574956 270)
			(size 0.519938 1.4986)
			(layers "F.Cu" "F.Mask" "F.Paste")
			(net "GND")
		)
		(pad "161" smd rect
			(at 2.050034 -49.725072 270)
			(size 0.519938 1.4986)
			(layers "F.Cu" "F.Mask" "F.Paste")
			(net "M_G_CPU0_SA_DQ<7>")
		)
		(pad "162" smd rect
			(at 2.050034 -48.874934 270)
			(size 0.519938 1.4986)
			(layers "F.Cu" "F.Mask" "F.Paste")
			(net "GND")
		)
		(pad "163" smd rect
			(at 2.050034 -48.02505 270)
			(size 0.519938 1.4986)
			(layers "F.Cu" "F.Mask" "F.Paste")
			(net "M_G_CPU0_SA_DQ<10>")
		)
		(pad "164" smd rect
			(at 2.050034 -47.174912 270)
			(size 0.519938 1.4986)
			(layers "F.Cu" "F.Mask" "F.Paste")
			(net "GND")
		)
		(pad "165" smd rect
			(at 2.050034 -46.325028 270)
			(size 0.519938 1.4986)
			(layers "F.Cu" "F.Mask" "F.Paste")
			(net "M_G_CPU0_SA_DQ<11>")
		)
		(pad "166" smd rect
			(at 2.050034 -45.47489 270)
			(size 0.519938 1.4986)
			(layers "F.Cu" "F.Mask" "F.Paste")
			(net "GND")
		)
		(pad "167" smd rect
			(at 2.050034 -44.625006 270)
			(size 0.519938 1.4986)
			(layers "F.Cu" "F.Mask" "F.Paste")
			(net "M_G_CPU0_SA_DQS_DN<6>")
		)
		(pad "168" smd rect
			(at 2.050034 -43.775122 270)
			(size 0.519938 1.4986)
			(layers "F.Cu" "F.Mask" "F.Paste")
			(net "M_G_CPU0_SA_DQS_DP<6>")
		)
		(pad "169" smd rect
			(at 2.050034 -42.924984 270)
			(size 0.519938 1.4986)
			(layers "F.Cu" "F.Mask" "F.Paste")
			(net "GND")
		)
		(pad "170" smd rect
			(at 2.050034 -42.0751 270)
			(size 0.519938 1.4986)
			(layers "F.Cu" "F.Mask" "F.Paste")
			(net "M_G_CPU0_SA_DQ<14>")
		)
		(pad "171" smd rect
			(at 2.050034 -41.224962 270)
			(size 0.519938 1.4986)
			(layers "F.Cu" "F.Mask" "F.Paste")
			(net "GND")
		)
		(pad "172" smd rect
			(at 2.050034 -40.375078 270)
			(size 0.519938 1.4986)
			(layers "F.Cu" "F.Mask" "F.Paste")
			(net "M_G_CPU0_SA_DQ<15>")
		)
		(pad "173" smd rect
			(at 2.050034 -39.52494 270)
			(size 0.519938 1.4986)
			(layers "F.Cu" "F.Mask" "F.Paste")
			(net "GND")
		)
		(pad "174" smd rect
			(at 2.050034 -38.675056 270)
			(size 0.519938 1.4986)
			(layers "F.Cu" "F.Mask" "F.Paste")
			(net "M_G_CPU0_SA_DQ<18>")
		)
		(pad "175" smd rect
			(at 2.050034 -37.824918 270)
			(size 0.519938 1.4986)
			(layers "F.Cu" "F.Mask" "F.Paste")
			(net "GND")
		)
		(pad "176" smd rect
			(at 2.050034 -36.975034 270)
			(size 0.519938 1.4986)
			(layers "F.Cu" "F.Mask" "F.Paste")
			(net "M_G_CPU0_SA_DQ<19>")
		)
		(pad "177" smd rect
			(at 2.050034 -36.124896 270)
			(size 0.519938 1.4986)
			(layers "F.Cu" "F.Mask" "F.Paste")
			(net "GND")
		)
		(pad "178" smd rect
			(at 2.050034 -35.275012 270)
			(size 0.519938 1.4986)
			(layers "F.Cu" "F.Mask" "F.Paste")
			(net "M_G_CPU0_SA_DQS_DN<7>")
		)
		(pad "179" smd rect
			(at 2.050034 -34.425128 270)
			(size 0.519938 1.4986)
			(layers "F.Cu" "F.Mask" "F.Paste")
			(net "M_G_CPU0_SA_DQS_DP<7>")
		)
		(pad "180" smd rect
			(at 2.050034 -33.57499 270)
			(size 0.519938 1.4986)
			(layers "F.Cu" "F.Mask" "F.Paste")
			(net "GND")
		)
		(pad "181" smd rect
			(at 2.050034 -32.725106 270)
			(size 0.519938 1.4986)
			(layers "F.Cu" "F.Mask" "F.Paste")
			(net "M_G_CPU0_SA_DQ<22>")
		)
		(pad "182" smd rect
			(at 2.050034 -31.874968 270)
			(size 0.519938 1.4986)
			(layers "F.Cu" "F.Mask" "F.Paste")
			(net "GND")
		)
	)
)
